(kicad_pcb
	(version 20260206)
	(generator "pcbnew")
	(generator_version "10.0")
	(general
		(thickness 1.6)
		(legacy_teardrops no)
	)
	(paper "A4")
	(title_block
		(title "Bryce Canyon_IOM_M2_16342-2_OCP.brd")
		(comment 1 "Bryce Canyon / footprints 321-328 of 1146")
	)
	(layers
		(0 "F.Cu" signal "TOP")
		(4 "In1.Cu" signal "L2GND")
		(6 "In2.Cu" signal "L3")
		(8 "In3.Cu" signal "L4VCC")
		(10 "In4.Cu" signal "L5VCC")
		(12 "In5.Cu" signal "L6")
		(14 "In6.Cu" signal "L7GND")
		(2 "B.Cu" signal "BOTTOM")
		(9 "F.Adhes" user "F.Adhesive")
		(11 "B.Adhes" user "B.Adhesive")
		(13 "F.Paste" user "Package Geometry/Pastemask Top")
		(15 "B.Paste" user "Package Geometry/Pastemask Bottom")
		(5 "F.SilkS" user "Ref Des/Silkscreen Top")
		(7 "B.SilkS" user "Ref Des/Silkscreen Bottom")
		(1 "F.Mask" user "Board Geometry/Soldermask Top")
		(3 "B.Mask" user "Board Geometry/Soldermask Bottom")
		(17 "Dwgs.User" user "User.Drawings")
		(19 "Cmts.User" user "User.Comments")
		(21 "Eco1.User" user "User.Eco1")
		(23 "Eco2.User" user "User.Eco2")
		(25 "Edge.Cuts" user "Board Geometry/Outline")
		(27 "Margin" user)
		(31 "F.CrtYd" user "Package Geometry/Place Bound Top")
		(29 "B.CrtYd" user "Package Geometry/Place Bound Bottom")
		(35 "F.Fab" user "Ref Des/Assembly Top")
		(33 "B.Fab" user "Ref Des/Assembly Bottom")
	)
	(footprint ""
		(layer "F.Cu")
		(at 29.806646 -176.618138 180)
		(property "Reference" "R494"
			(at 0 0 180)
			(layer "F.SilkS")
			(hide yes)
			(effects
				(font
					(size 1.27 1.27)
				)
			)
		)
		(property "Value" "57K6R2D-GP"
			(at 0.064008 -3.993896 180)
			(unlocked yes)
			(layer "F.Fab")
			(hide yes)
			(effects
				(font
					(size 1.016 1.016)
					(thickness 0.1524)
				)
			)
		)
		(property "Device Type" "R402H16"
			(at 0.064008 -5.517896 180)
			(unlocked yes)
			(layer "F.Fab")
			(hide yes)
			(effects
				(font
					(size 1.016 1.016)
					(thickness 0.1524)
				)
			)
		)
		(duplicate_pad_numbers_are_jumpers no)
		(fp_line
			(start 0.508 -0.9398)
			(end -0.508 -0.9398)
			(stroke
				(width 0.1524)
				(type default)
			)
			(layer "F.SilkS")
		)
		(fp_line
			(start -0.508 -0.9398)
			(end -0.508 0.9398)
			(stroke
				(width 0.1524)
				(type default)
			)
			(layer "F.SilkS")
		)
		(fp_rect
			(start -0.508 0.9398)
			(end 0.508 -0.9398)
			(stroke
				(width 0)
				(type default)
			)
			(fill no)
			(layer "F.CrtYd")
		)
		(fp_rect
			(start -0.508 0.9398)
			(end 0.508 -0.9398)
			(stroke
				(width 0)
				(type default)
			)
			(fill no)
			(layer "F.Fab")
		)
		(pad "1" smd custom
			(at 0 -0.4445 180)
			(size 0.1397 0.1397)
			(layers "F.Cu" "F.Mask" "F.Paste")
			(net "AGND_P3V3_STBY")
			(options
				(clearance outline)
				(anchor circle)
			)
			(primitives
				(gr_poly
					(pts
						(arc
							(start -0.1778 -0.2794)
							(mid -0.249642 -0.249642)
							(end -0.2794 -0.1778)
						)
						(arc
							(start -0.2794 0.1778)
							(mid -0.249642 0.249642)
							(end -0.1778 0.2794)
						)
						(arc
							(start 0.1778 0.2794)
							(mid 0.249642 0.249642)
							(end 0.2794 0.1778)
						)
						(arc
							(start 0.2794 -0.1778)
							(mid 0.249642 -0.249642)
							(end 0.1778 -0.2794)
						)
					)
					(width 0)
					(fill yes)
				)
			)
		)
		(pad "2" smd custom
			(at 0 0.4445 180)
			(size 0.1397 0.1397)
			(layers "F.Cu" "F.Mask" "F.Paste")
			(net "P3V3_STBY_TRIP")
			(options
				(clearance outline)
				(anchor circle)
			)
			(primitives
				(gr_poly
					(pts
						(arc
							(start -0.1778 -0.2794)
							(mid -0.249642 -0.249642)
							(end -0.2794 -0.1778)
						)
						(arc
							(start -0.2794 0.1778)
							(mid -0.249642 0.249642)
							(end -0.1778 0.2794)
						)
						(arc
							(start 0.1778 0.2794)
							(mid 0.249642 0.249642)
							(end 0.2794 0.1778)
						)
						(arc
							(start 0.2794 -0.1778)
							(mid 0.249642 -0.249642)
							(end 0.1778 -0.2794)
						)
					)
					(width 0)
					(fill yes)
				)
			)
		)
	)
	(footprint ""
		(layer "F.Cu")
		(at 77.283818 -93.355668 90)
		(property "Reference" "VIA8"
			(at 0 0 90)
			(layer "F.SilkS")
			(hide yes)
			(effects
				(font
					(size 1.27 1.27)
				)
			)
		)
		(property "Value" "85OHM-8L-1D6MM-L16L18-GP"
			(at 4.064 0.6096 90)
			(unlocked yes)
			(layer "F.Fab")
			(hide yes)
			(effects
				(font
					(size 1.016 1.016)
					(thickness 0.1524)
				)
			)
		)
		(property "Device Type" "VIA-PCIE-4P-368076"
			(at 4.064 -0.9144 90)
			(unlocked yes)
			(layer "F.Fab")
			(hide yes)
			(effects
				(font
					(size 1.016 1.016)
					(thickness 0.1524)
				)
			)
		)
		(duplicate_pad_numbers_are_jumpers no)
		(fp_rect
			(start -1.8415 0.381)
			(end 1.8415 -0.381)
			(stroke
				(width 0)
				(type default)
			)
			(fill no)
			(layer "F.CrtYd")
		)
		(fp_rect
			(start -1.8415 0.381)
			(end 1.8415 -0.381)
			(stroke
				(width 0)
				(type default)
			)
			(fill no)
			(layer "F.Fab")
		)
		(pad "1" thru_hole circle
			(at -1.4605 0 90)
			(size 0.508 0.508)
			(drill 0.254)
			(layers "*.Cu" "*.Mask")
			(remove_unused_layers no)
			(net "GND")
			(clearance 0.127)
			(thermal_gap 0.127)
		)
		(pad "2" thru_hole circle
			(at -0.4445 0 90)
			(size 0.508 0.508)
			(drill 0.254)
			(layers "*.Cu" "*.Mask")
			(remove_unused_layers no)
			(net "PCIE_COMP_TO_IOM_23_DP")
			(clearance 0.127)
			(thermal_gap 0.127)
		)
		(pad "3" thru_hole circle
			(at 0.4445 0 90)
			(size 0.508 0.508)
			(drill 0.254)
			(layers "*.Cu" "*.Mask")
			(remove_unused_layers no)
			(net "PCIE_COMP_TO_IOM_23_DN")
			(clearance 0.127)
			(thermal_gap 0.127)
		)
		(pad "4" thru_hole circle
			(at 1.4605 0 90)
			(size 0.508 0.508)
			(drill 0.254)
			(layers "*.Cu" "*.Mask")
			(remove_unused_layers no)
			(net "GND")
			(clearance 0.127)
			(thermal_gap 0.127)
		)
	)
	(footprint ""
		(layer "F.Cu")
		(at 77.355192 -67.756532 90)
		(property "Reference" "VIA25"
			(at 0 0 90)
			(layer "F.SilkS")
			(hide yes)
			(effects
				(font
					(size 1.27 1.27)
				)
			)
		)
		(property "Value" "85OHM-8L-1D6MM-L16L18-GP"
			(at 4.064 0.6096 90)
			(unlocked yes)
			(layer "F.Fab")
			(hide yes)
			(effects
				(font
					(size 1.016 1.016)
					(thickness 0.1524)
				)
			)
		)
		(property "Device Type" "VIA-PCIE-4P-368076"
			(at 4.064 -0.9144 90)
			(unlocked yes)
			(layer "F.Fab")
			(hide yes)
			(effects
				(font
					(size 1.016 1.016)
					(thickness 0.1524)
				)
			)
		)
		(duplicate_pad_numbers_are_jumpers no)
		(fp_rect
			(start -1.8415 0.381)
			(end 1.8415 -0.381)
			(stroke
				(width 0)
				(type default)
			)
			(fill no)
			(layer "F.CrtYd")
		)
		(fp_rect
			(start -1.8415 0.381)
			(end 1.8415 -0.381)
			(stroke
				(width 0)
				(type default)
			)
			(fill no)
			(layer "F.Fab")
		)
		(pad "1" thru_hole circle
			(at -1.4605 0 90)
			(size 0.508 0.508)
			(drill 0.254)
			(layers "*.Cu" "*.Mask")
			(remove_unused_layers no)
			(net "GND")
			(clearance 0.127)
			(thermal_gap 0.127)
		)
		(pad "2" thru_hole circle
			(at -0.4445 0 90)
			(size 0.508 0.508)
			(drill 0.254)
			(layers "*.Cu" "*.Mask")
			(remove_unused_layers no)
			(net "PCIE_COMP_TO_IOM_CLK_4_DP")
			(clearance 0.127)
			(thermal_gap 0.127)
		)
		(pad "3" thru_hole circle
			(at 0.4445 0 90)
			(size 0.508 0.508)
			(drill 0.254)
			(layers "*.Cu" "*.Mask")
			(remove_unused_layers no)
			(net "PCIE_COMP_TO_IOM_CLK_4_DN")
			(clearance 0.127)
			(thermal_gap 0.127)
		)
		(pad "4" thru_hole circle
			(at 1.4605 0 90)
			(size 0.508 0.508)
			(drill 0.254)
			(layers "*.Cu" "*.Mask")
			(remove_unused_layers no)
			(net "GND")
			(clearance 0.127)
			(thermal_gap 0.127)
		)
	)
	(footprint ""
		(layer "F.Cu")
		(at 152.132538 -16.816578 180)
		(property "Reference" "R511"
			(at 0 0 180)
			(layer "F.SilkS")
			(hide yes)
			(effects
				(font
					(size 1.27 1.27)
				)
			)
		)
		(property "Value" "2D2R3-1-U-GP"
			(at -0.0254 -2.5146 180)
			(unlocked yes)
			(layer "F.Fab")
			(hide yes)
			(effects
				(font
					(size 1.016 1.016)
					(thickness 0.1524)
				)
			)
		)
		(property "Device Type" "R603H22"
			(at -0.0254 -4.0386 180)
			(unlocked yes)
			(layer "F.Fab")
			(hide yes)
			(effects
				(font
					(size 1.016 1.016)
					(thickness 0.1524)
				)
			)
		)
		(duplicate_pad_numbers_are_jumpers no)
		(fp_line
			(start 0.2032 0)
			(end 0.4826 0)
			(stroke
				(width 0.2032)
				(type default)
			)
			(layer "F.SilkS")
		)
		(fp_line
			(start -0.4826 0)
			(end -0.2032 0)
			(stroke
				(width 0.2032)
				(type default)
			)
			(layer "F.SilkS")
		)
		(fp_rect
			(start -0.5842 1.3335)
			(end 0.5842 -1.3335)
			(stroke
				(width 0)
				(type default)
			)
			(fill no)
			(layer "F.CrtYd")
		)
		(fp_rect
			(start -0.5842 1.3335)
			(end 0.5842 -1.3335)
			(stroke
				(width 0)
				(type default)
			)
			(fill no)
			(layer "F.Fab")
		)
		(pad "1" smd custom
			(at 0 -0.762 180)
			(size 0.2159 0.2159)
			(layers "F.Cu" "F.Mask" "F.Paste")
			(net "P12V_STBY_VCC_PU4")
			(options
				(clearance outline)
				(anchor circle)
			)
			(primitives
				(gr_poly
					(pts
						(arc
							(start -0.3302 -0.4318)
							(mid -0.402042 -0.402042)
							(end -0.4318 -0.3302)
						)
						(arc
							(start -0.4318 0.3302)
							(mid -0.402042 0.402042)
							(end -0.3302 0.4318)
						)
						(arc
							(start 0.3302 0.4318)
							(mid 0.402042 0.402042)
							(end 0.4318 0.3302)
						)
						(arc
							(start 0.4318 -0.3302)
							(mid 0.402042 -0.402042)
							(end 0.3302 -0.4318)
						)
					)
					(width 0)
					(fill yes)
				)
			)
		)
		(pad "2" smd custom
			(at 0 0.762 180)
			(size 0.2159 0.2159)
			(layers "F.Cu" "F.Mask" "F.Paste")
			(net "P12V_STBY")
			(options
				(clearance outline)
				(anchor circle)
			)
			(primitives
				(gr_poly
					(pts
						(arc
							(start -0.3302 -0.4318)
							(mid -0.402042 -0.402042)
							(end -0.4318 -0.3302)
						)
						(arc
							(start -0.4318 0.3302)
							(mid -0.402042 0.402042)
							(end -0.3302 0.4318)
						)
						(arc
							(start 0.3302 0.4318)
							(mid 0.402042 0.402042)
							(end 0.4318 0.3302)
						)
						(arc
							(start 0.4318 -0.3302)
							(mid 0.402042 -0.402042)
							(end 0.3302 -0.4318)
						)
					)
					(width 0)
					(fill yes)
				)
			)
		)
	)
	(footprint ""
		(layer "F.Cu")
		(at 115.135152 -13.848588 -90)
		(property "Reference" "C128"
			(at 0 0 270)
			(layer "F.SilkS")
			(hide yes)
			(effects
				(font
					(size 1.27 1.27)
				)
			)
		)
		(property "Value" "SC1U25V3KX-GP"
			(at 0 -2.8194 270)
			(unlocked yes)
			(layer "F.Fab")
			(hide yes)
			(effects
				(font
					(size 1.016 1.016)
					(thickness 0.1524)
				)
			)
		)
		(property "Device Type" "C603H36"
			(at 0 -4.3434 270)
			(unlocked yes)
			(layer "F.Fab")
			(hide yes)
			(effects
				(font
					(size 1.016 1.016)
					(thickness 0.1524)
				)
			)
		)
		(duplicate_pad_numbers_are_jumpers no)
		(fp_line
			(start 0.508 0)
			(end -0.508 0)
			(stroke
				(width 0.2032)
				(type default)
			)
			(layer "F.SilkS")
		)
		(fp_rect
			(start -0.5842 1.3335)
			(end 0.5842 -1.3335)
			(stroke
				(width 0)
				(type default)
			)
			(fill no)
			(layer "F.CrtYd")
		)
		(fp_rect
			(start -0.5842 1.3335)
			(end 0.5842 -1.3335)
			(stroke
				(width 0)
				(type default)
			)
			(fill no)
			(layer "F.Fab")
		)
		(pad "1" smd custom
			(at 0 -0.762 270)
			(size 0.2159 0.2159)
			(layers "F.Cu" "F.Mask" "F.Paste")
			(net "MB0_VCC")
			(options
				(clearance outline)
				(anchor circle)
			)
			(primitives
				(gr_poly
					(pts
						(arc
							(start -0.3302 -0.4318)
							(mid -0.402042 -0.402042)
							(end -0.4318 -0.3302)
						)
						(arc
							(start -0.4318 0.3302)
							(mid -0.402042 0.402042)
							(end -0.3302 0.4318)
						)
						(arc
							(start 0.3302 0.4318)
							(mid 0.402042 0.402042)
							(end 0.4318 0.3302)
						)
						(arc
							(start 0.4318 -0.3302)
							(mid 0.402042 -0.402042)
							(end 0.3302 -0.4318)
						)
					)
					(width 0)
					(fill yes)
				)
			)
		)
		(pad "2" smd custom
			(at 0 0.762 270)
			(size 0.2159 0.2159)
			(layers "F.Cu" "F.Mask" "F.Paste")
			(net "AGND_CURRENT_MON")
			(options
				(clearance outline)
				(anchor circle)
			)
			(primitives
				(gr_poly
					(pts
						(arc
							(start -0.3302 -0.4318)
							(mid -0.402042 -0.402042)
							(end -0.4318 -0.3302)
						)
						(arc
							(start -0.4318 0.3302)
							(mid -0.402042 0.402042)
							(end -0.3302 0.4318)
						)
						(arc
							(start 0.3302 0.4318)
							(mid 0.402042 0.402042)
							(end 0.4318 0.3302)
						)
						(arc
							(start 0.4318 -0.3302)
							(mid 0.402042 -0.402042)
							(end 0.3302 -0.4318)
						)
					)
					(width 0)
					(fill yes)
				)
			)
		)
	)
	(footprint ""
		(layer "F.Cu")
		(at 12.2428 -172.030136)
		(property "Reference" "R534"
			(at 0 0 0)
			(layer "F.SilkS")
			(hide yes)
			(effects
				(font
					(size 1.27 1.27)
				)
			)
		)
		(property "Value" "4K75R2F-1-GP"
			(at 0.064008 -3.993896 0)
			(unlocked yes)
			(layer "F.Fab")
			(hide yes)
			(effects
				(font
					(size 1.016 1.016)
					(thickness 0.1524)
				)
			)
		)
		(property "Device Type" "R402H16"
			(at 0.064008 -5.517896 0)
			(unlocked yes)
			(layer "F.Fab")
			(hide yes)
			(effects
				(font
					(size 1.016 1.016)
					(thickness 0.1524)
				)
			)
		)
		(duplicate_pad_numbers_are_jumpers no)
		(fp_line
			(start -0.508 -0.9398)
			(end -0.508 0.9398)
			(stroke
				(width 0.1524)
				(type default)
			)
			(layer "F.SilkS")
		)
		(fp_line
			(start 0.508 -0.9398)
			(end -0.508 -0.9398)
			(stroke
				(width 0.1524)
				(type default)
			)
			(layer "F.SilkS")
		)
		(fp_rect
			(start -0.508 0.9398)
			(end 0.508 -0.9398)
			(stroke
				(width 0)
				(type default)
			)
			(fill no)
			(layer "F.CrtYd")
		)
		(fp_rect
			(start -0.508 0.9398)
			(end 0.508 -0.9398)
			(stroke
				(width 0)
				(type default)
			)
			(fill no)
			(layer "F.Fab")
		)
		(pad "1" smd custom
			(at 0 -0.4445)
			(size 0.1397 0.1397)
			(layers "F.Cu" "F.Mask" "F.Paste")
			(net "P3V3_STBY")
			(options
				(clearance outline)
				(anchor circle)
			)
			(primitives
				(gr_poly
					(pts
						(arc
							(start -0.1778 -0.2794)
							(mid -0.249642 -0.249642)
							(end -0.2794 -0.1778)
						)
						(arc
							(start -0.2794 0.1778)
							(mid -0.249642 0.249642)
							(end -0.1778 0.2794)
						)
						(arc
							(start 0.1778 0.2794)
							(mid 0.249642 0.249642)
							(end 0.2794 0.1778)
						)
						(arc
							(start 0.2794 -0.1778)
							(mid 0.249642 -0.249642)
							(end 0.1778 -0.2794)
						)
					)
					(width 0)
					(fill yes)
				)
			)
		)
		(pad "2" smd custom
			(at 0 0.4445)
			(size 0.1397 0.1397)
			(layers "F.Cu" "F.Mask" "F.Paste")
			(net "TPS74801_P1V2_STBY_EN")
			(options
				(clearance outline)
				(anchor circle)
			)
			(primitives
				(gr_poly
					(pts
						(arc
							(start -0.1778 -0.2794)
							(mid -0.249642 -0.249642)
							(end -0.2794 -0.1778)
						)
						(arc
							(start -0.2794 0.1778)
							(mid -0.249642 0.249642)
							(end -0.1778 0.2794)
						)
						(arc
							(start 0.1778 0.2794)
							(mid 0.249642 0.249642)
							(end 0.2794 0.1778)
						)
						(arc
							(start 0.2794 -0.1778)
							(mid 0.249642 -0.249642)
							(end 0.1778 -0.2794)
						)
					)
					(width 0)
					(fill yes)
				)
			)
		)
	)
	(footprint ""
		(layer "F.Cu")
		(at 54.0004 -131.7498)
		(property "Reference" "R147"
			(at 0 0 0)
			(layer "F.SilkS")
			(hide yes)
			(effects
				(font
					(size 1.27 1.27)
				)
			)
		)
		(property "Value" "100KR2F-L1-GP"
			(at 0.064008 -3.993896 0)
			(unlocked yes)
			(layer "F.Fab")
			(hide yes)
			(effects
				(font
					(size 1.016 1.016)
					(thickness 0.1524)
				)
			)
		)
		(property "Device Type" "R402H16"
			(at 0.064008 -5.517896 0)
			(unlocked yes)
			(layer "F.Fab")
			(hide yes)
			(effects
				(font
					(size 1.016 1.016)
					(thickness 0.1524)
				)
			)
		)
		(duplicate_pad_numbers_are_jumpers no)
		(fp_line
			(start -0.508 -0.9398)
			(end -0.508 0.9398)
			(stroke
				(width 0.1524)
				(type default)
			)
			(layer "F.SilkS")
		)
		(fp_line
			(start 0.508 -0.9398)
			(end -0.508 -0.9398)
			(stroke
				(width 0.1524)
				(type default)
			)
			(layer "F.SilkS")
		)
		(fp_rect
			(start -0.508 0.9398)
			(end 0.508 -0.9398)
			(stroke
				(width 0)
				(type default)
			)
			(fill no)
			(layer "F.CrtYd")
		)
		(fp_rect
			(start -0.508 0.9398)
			(end 0.508 -0.9398)
			(stroke
				(width 0)
				(type default)
			)
			(fill no)
			(layer "F.Fab")
		)
		(pad "1" smd custom
			(at 0 -0.4445)
			(size 0.1397 0.1397)
			(layers "F.Cu" "F.Mask" "F.Paste")
			(net "LPC_CPU_FRAME_N")
			(options
				(clearance outline)
				(anchor circle)
			)
			(primitives
				(gr_poly
					(pts
						(arc
							(start -0.1778 -0.2794)
							(mid -0.249642 -0.249642)
							(end -0.2794 -0.1778)
						)
						(arc
							(start -0.2794 0.1778)
							(mid -0.249642 0.249642)
							(end -0.1778 0.2794)
						)
						(arc
							(start 0.1778 0.2794)
							(mid 0.249642 0.249642)
							(end 0.2794 0.1778)
						)
						(arc
							(start 0.2794 -0.1778)
							(mid 0.249642 -0.249642)
							(end 0.1778 -0.2794)
						)
					)
					(width 0)
					(fill yes)
				)
			)
		)
		(pad "2" smd custom
			(at 0 0.4445)
			(size 0.1397 0.1397)
			(layers "F.Cu" "F.Mask" "F.Paste")
			(net "GND")
			(options
				(clearance outline)
				(anchor circle)
			)
			(primitives
				(gr_poly
					(pts
						(arc
							(start -0.1778 -0.2794)
							(mid -0.249642 -0.249642)
							(end -0.2794 -0.1778)
						)
						(arc
							(start -0.2794 0.1778)
							(mid -0.249642 0.249642)
							(end -0.1778 0.2794)
						)
						(arc
							(start 0.1778 0.2794)
							(mid 0.249642 0.249642)
							(end 0.2794 0.1778)
						)
						(arc
							(start 0.2794 -0.1778)
							(mid 0.249642 -0.249642)
							(end 0.1778 -0.2794)
						)
					)
					(width 0)
					(fill yes)
				)
			)
		)
	)
	(footprint ""
		(layer "F.Cu")
		(at 99.297744 -159.65932 -90)
		(property "Reference" "R20"
			(at 0 0 270)
			(layer "F.SilkS")
			(hide yes)
			(effects
				(font
					(size 1.27 1.27)
				)
			)
		)
		(property "Value" "4K7R2F-GP"
			(at 0.064008 -3.993896 270)
			(unlocked yes)
			(layer "F.Fab")
			(hide yes)
			(effects
				(font
					(size 1.016 1.016)
					(thickness 0.1524)
				)
			)
		)
		(property "Device Type" "R402H16"
			(at 0.064008 -5.517896 270)
			(unlocked yes)
			(layer "F.Fab")
			(hide yes)
			(effects
				(font
					(size 1.016 1.016)
					(thickness 0.1524)
				)
			)
		)
		(duplicate_pad_numbers_are_jumpers no)
		(fp_line
			(start -0.508 -0.9398)
			(end -0.508 0.9398)
			(stroke
				(width 0.1524)
				(type default)
			)
			(layer "F.SilkS")
		)
		(fp_line
			(start 0.508 -0.9398)
			(end -0.508 -0.9398)
			(stroke
				(width 0.1524)
				(type default)
			)
			(layer "F.SilkS")
		)
		(fp_rect
			(start -0.508 0.9398)
			(end 0.508 -0.9398)
			(stroke
				(width 0)
				(type default)
			)
			(fill no)
			(layer "F.CrtYd")
		)
		(fp_rect
			(start -0.508 0.9398)
			(end 0.508 -0.9398)
			(stroke
				(width 0)
				(type default)
			)
			(fill no)
			(layer "F.Fab")
		)
		(pad "1" smd custom
			(at 0 -0.4445 270)
			(size 0.1397 0.1397)
			(layers "F.Cu" "F.Mask" "F.Paste")
			(net "P3V3_STBY")
			(options
				(clearance outline)
				(anchor circle)
			)
			(primitives
				(gr_poly
					(pts
						(arc
							(start -0.1778 -0.2794)
							(mid -0.249642 -0.249642)
							(end -0.2794 -0.1778)
						)
						(arc
							(start -0.2794 0.1778)
							(mid -0.249642 0.249642)
							(end -0.1778 0.2794)
						)
						(arc
							(start 0.1778 0.2794)
							(mid 0.249642 0.249642)
							(end 0.2794 0.1778)
						)
						(arc
							(start 0.2794 -0.1778)
							(mid 0.249642 -0.249642)
							(end 0.1778 -0.2794)
						)
					)
					(width 0)
					(fill yes)
				)
			)
		)
		(pad "2" smd custom
			(at 0 0.4445 270)
			(size 0.1397 0.1397)
			(layers "F.Cu" "F.Mask" "F.Paste")
			(net "VBUS_DET")
			(options
				(clearance outline)
				(anchor circle)
			)
			(primitives
				(gr_poly
					(pts
						(arc
							(start -0.1778 -0.2794)
							(mid -0.249642 -0.249642)
							(end -0.2794 -0.1778)
						)
						(arc
							(start -0.2794 0.1778)
							(mid -0.249642 0.249642)
							(end -0.1778 0.2794)
						)
						(arc
							(start 0.1778 0.2794)
							(mid 0.249642 0.249642)
							(end 0.2794 0.1778)
						)
						(arc
							(start 0.2794 -0.1778)
							(mid 0.249642 -0.249642)
							(end 0.1778 -0.2794)
						)
					)
					(width 0)
					(fill yes)
				)
			)
		)
	)
)
